(kicad_pcb
	(version 20260206)
	(generator "pcbnew")
	(generator_version "10.0")
	(general
		(thickness 1.6)
		(legacy_teardrops no)
	)
	(paper "A4")
	(title_block
		(title "baseboard — 13948-1b.1110WZS1818.brd")
		(comment 1 "Honey Badger (Wiwynn) / footprints 2189-2195 of 2523")
	)
	(layers
		(0 "F.Cu" signal "TOP")
		(4 "In1.Cu" signal "L2GND")
		(6 "In2.Cu" signal "L3")
		(8 "In3.Cu" signal "L4VCC")
		(10 "In4.Cu" signal "L5VCC")
		(12 "In5.Cu" signal "L6")
		(14 "In6.Cu" signal "L7GND")
		(2 "B.Cu" signal "BOTTOM")
		(9 "F.Adhes" user "F.Adhesive")
		(11 "B.Adhes" user "B.Adhesive")
		(13 "F.Paste" user "Package Geometry/Pastemask Top")
		(15 "B.Paste" user "Package Geometry/Pastemask Bottom")
		(5 "F.SilkS" user "Ref Des/Silkscreen Top")
		(7 "B.SilkS" user "Ref Des/Silkscreen Bottom")
		(1 "F.Mask" user "Board Geometry/Soldermask Top")
		(3 "B.Mask" user "Board Geometry/Soldermask Bottom")
		(17 "Dwgs.User" user "User.Drawings")
		(19 "Cmts.User" user "User.Comments")
		(21 "Eco1.User" user "User.Eco1")
		(23 "Eco2.User" user "User.Eco2")
		(25 "Edge.Cuts" user "Board Geometry/Outline")
		(27 "Margin" user)
		(31 "F.CrtYd" user "Package Geometry/Place Bound Top")
		(29 "B.CrtYd" user "Package Geometry/Place Bound Bottom")
		(35 "F.Fab" user "Ref Des/Assembly Top")
		(33 "B.Fab" user "Ref Des/Assembly Bottom")
	)
	(footprint ""
		(layer "B.Cu")
		(at 164.211 -114.427)
		(property "Reference" "SR854"
			(at 0 0 0)
			(layer "B.SilkS")
			(hide yes)
			(effects
				(font
					(size 1.27 1.27)
				)
				(justify mirror)
			)
		)
		(property "Value" "4K7R2F-GP"
			(at -0.064008 -3.993896 0)
			(unlocked yes)
			(layer "B.Fab")
			(hide yes)
			(effects
				(font
					(size 1.016 1.016)
					(thickness 0.1524)
				)
				(justify mirror)
			)
		)
		(property "Device Type" "R402H16"
			(at -0.064008 -5.517896 0)
			(unlocked yes)
			(layer "B.Fab")
			(hide yes)
			(effects
				(font
					(size 1.016 1.016)
					(thickness 0.1524)
				)
				(justify mirror)
			)
		)
		(duplicate_pad_numbers_are_jumpers no)
		(fp_line
			(start -0.508 -0.9398)
			(end 0.508 -0.9398)
			(stroke
				(width 0.1524)
				(type default)
			)
			(layer "B.SilkS")
		)
		(fp_line
			(start 0.508 -0.9398)
			(end 0.508 0.9398)
			(stroke
				(width 0.1524)
				(type default)
			)
			(layer "B.SilkS")
		)
		(fp_rect
			(start 0.508 0.9398)
			(end -0.508 -0.9398)
			(stroke
				(width 0)
				(type default)
			)
			(fill no)
			(layer "B.CrtYd")
		)
		(fp_rect
			(start 0.508 0.9398)
			(end -0.508 -0.9398)
			(stroke
				(width 0)
				(type default)
			)
			(fill no)
			(layer "B.Fab")
		)
		(pad "1" smd custom
			(at 0 -0.4445 180)
			(size 0.1397 0.1397)
			(layers "B.Cu" "B.Mask" "B.Paste")
			(net "P3V3_STBY")
			(options
				(clearance outline)
				(anchor circle)
			)
			(primitives
				(gr_poly
					(pts
						(arc
							(start -0.1778 0.2794)
							(mid -0.249642 0.249642)
							(end -0.2794 0.1778)
						)
						(arc
							(start -0.2794 -0.1778)
							(mid -0.249642 -0.249642)
							(end -0.1778 -0.2794)
						)
						(arc
							(start 0.1778 -0.2794)
							(mid 0.249642 -0.249642)
							(end 0.2794 -0.1778)
						)
						(arc
							(start 0.2794 0.1778)
							(mid 0.249642 0.249642)
							(end 0.1778 0.2794)
						)
					)
					(width 0)
					(fill yes)
				)
			)
		)
		(pad "2" smd custom
			(at 0 0.4445 180)
			(size 0.1397 0.1397)
			(layers "B.Cu" "B.Mask" "B.Paste")
			(net "P3V3_STBY_R4")
			(options
				(clearance outline)
				(anchor circle)
			)
			(primitives
				(gr_poly
					(pts
						(arc
							(start -0.1778 0.2794)
							(mid -0.249642 0.249642)
							(end -0.2794 0.1778)
						)
						(arc
							(start -0.2794 -0.1778)
							(mid -0.249642 -0.249642)
							(end -0.1778 -0.2794)
						)
						(arc
							(start 0.1778 -0.2794)
							(mid 0.249642 -0.249642)
							(end 0.2794 -0.1778)
						)
						(arc
							(start 0.2794 0.1778)
							(mid 0.249642 0.249642)
							(end 0.1778 0.2794)
						)
					)
					(width 0)
					(fill yes)
				)
			)
		)
	)
	(footprint ""
		(layer "B.Cu")
		(at 350.393 -81.534 180)
		(property "Reference" "C186"
			(at 0 0 0)
			(layer "B.SilkS")
			(hide yes)
			(effects
				(font
					(size 1.27 1.27)
				)
				(justify mirror)
			)
		)
		(property "Value" "SCD1U16V2KX-3GP"
			(at -1.1811 -2.7051 180)
			(unlocked yes)
			(layer "B.Fab")
			(hide yes)
			(effects
				(font
					(size 1.016 1.016)
					(thickness 0.1524)
				)
				(justify mirror)
			)
		)
		(property "Device Type" "C402H22"
			(at -1.1811 -4.2291 180)
			(unlocked yes)
			(layer "B.Fab")
			(hide yes)
			(effects
				(font
					(size 1.016 1.016)
					(thickness 0.1524)
				)
				(justify mirror)
			)
		)
		(duplicate_pad_numbers_are_jumpers no)
		(fp_rect
			(start 0.4318 0.9525)
			(end -0.4318 -0.9525)
			(stroke
				(width 0)
				(type default)
			)
			(fill no)
			(layer "B.CrtYd")
		)
		(fp_rect
			(start 0.4318 0.9525)
			(end -0.4318 -0.9525)
			(stroke
				(width 0)
				(type default)
			)
			(fill no)
			(layer "B.Fab")
		)
		(pad "1" smd custom
			(at 0 -0.4445)
			(size 0.1524 0.1524)
			(layers "B.Cu" "B.Mask" "B.Paste")
			(net "P3V3_STBY")
			(options
				(clearance outline)
				(anchor circle)
			)
			(primitives
				(gr_poly
					(pts
						(arc
							(start 0.3048 0.2032)
							(mid 0.275042 0.275042)
							(end 0.2032 0.3048)
						)
						(arc
							(start -0.2032 0.3048)
							(mid -0.275042 0.275042)
							(end -0.3048 0.2032)
						)
						(arc
							(start -0.3048 -0.2032)
							(mid -0.275042 -0.275042)
							(end -0.2032 -0.3048)
						)
						(arc
							(start 0.2032 -0.3048)
							(mid 0.275042 -0.275042)
							(end 0.3048 -0.2032)
						)
					)
					(width 0)
					(fill yes)
				)
			)
		)
		(pad "2" smd custom
			(at 0 0.4445)
			(size 0.1524 0.1524)
			(layers "B.Cu" "B.Mask" "B.Paste")
			(net "GND")
			(options
				(clearance outline)
				(anchor circle)
			)
			(primitives
				(gr_poly
					(pts
						(arc
							(start 0.3048 0.2032)
							(mid 0.275042 0.275042)
							(end 0.2032 0.3048)
						)
						(arc
							(start -0.2032 0.3048)
							(mid -0.275042 0.275042)
							(end -0.3048 0.2032)
						)
						(arc
							(start -0.3048 -0.2032)
							(mid -0.275042 -0.275042)
							(end -0.2032 -0.3048)
						)
						(arc
							(start 0.2032 -0.3048)
							(mid 0.275042 -0.275042)
							(end 0.3048 -0.2032)
						)
					)
					(width 0)
					(fill yes)
				)
			)
		)
	)
	(footprint ""
		(layer "B.Cu")
		(at 103.359966 -58.928 180)
		(property "Reference" "SR682"
			(at 0 0 0)
			(layer "B.SilkS")
			(hide yes)
			(effects
				(font
					(size 1.27 1.27)
				)
				(justify mirror)
			)
		)
		(property "Value" "10KR2F-2-GP"
			(at -0.064008 -3.993896 180)
			(unlocked yes)
			(layer "B.Fab")
			(hide yes)
			(effects
				(font
					(size 1.016 1.016)
					(thickness 0.1524)
				)
				(justify mirror)
			)
		)
		(property "Device Type" "R402H16"
			(at -0.064008 -5.517896 180)
			(unlocked yes)
			(layer "B.Fab")
			(hide yes)
			(effects
				(font
					(size 1.016 1.016)
					(thickness 0.1524)
				)
				(justify mirror)
			)
		)
		(duplicate_pad_numbers_are_jumpers no)
		(fp_line
			(start 0.508 -0.9398)
			(end 0.508 0.9398)
			(stroke
				(width 0.1524)
				(type default)
			)
			(layer "B.SilkS")
		)
		(fp_line
			(start -0.508 -0.9398)
			(end 0.508 -0.9398)
			(stroke
				(width 0.1524)
				(type default)
			)
			(layer "B.SilkS")
		)
		(fp_rect
			(start 0.508 0.9398)
			(end -0.508 -0.9398)
			(stroke
				(width 0)
				(type default)
			)
			(fill no)
			(layer "B.CrtYd")
		)
		(fp_rect
			(start 0.508 0.9398)
			(end -0.508 -0.9398)
			(stroke
				(width 0)
				(type default)
			)
			(fill no)
			(layer "B.Fab")
		)
		(pad "1" smd custom
			(at 0 -0.4445)
			(size 0.1397 0.1397)
			(layers "B.Cu" "B.Mask" "B.Paste")
			(net "LSI_IDDT")
			(options
				(clearance outline)
				(anchor circle)
			)
			(primitives
				(gr_poly
					(pts
						(arc
							(start -0.1778 0.2794)
							(mid -0.249642 0.249642)
							(end -0.2794 0.1778)
						)
						(arc
							(start -0.2794 -0.1778)
							(mid -0.249642 -0.249642)
							(end -0.1778 -0.2794)
						)
						(arc
							(start 0.1778 -0.2794)
							(mid 0.249642 -0.249642)
							(end 0.2794 -0.1778)
						)
						(arc
							(start 0.2794 0.1778)
							(mid 0.249642 0.249642)
							(end 0.1778 0.2794)
						)
					)
					(width 0)
					(fill yes)
				)
			)
		)
		(pad "2" smd custom
			(at 0 0.4445)
			(size 0.1397 0.1397)
			(layers "B.Cu" "B.Mask" "B.Paste")
			(net "GND")
			(options
				(clearance outline)
				(anchor circle)
			)
			(primitives
				(gr_poly
					(pts
						(arc
							(start -0.1778 0.2794)
							(mid -0.249642 0.249642)
							(end -0.2794 0.1778)
						)
						(arc
							(start -0.2794 -0.1778)
							(mid -0.249642 -0.249642)
							(end -0.1778 -0.2794)
						)
						(arc
							(start 0.1778 -0.2794)
							(mid 0.249642 -0.249642)
							(end 0.2794 -0.1778)
						)
						(arc
							(start 0.2794 0.1778)
							(mid 0.249642 0.249642)
							(end 0.1778 0.2794)
						)
					)
					(width 0)
					(fill yes)
				)
			)
		)
	)
	(footprint ""
		(layer "B.Cu")
		(at 269.748 -30.607 -90)
		(property "Reference" "PC50"
			(at 0 0 90)
			(layer "B.SilkS")
			(hide yes)
			(effects
				(font
					(size 1.27 1.27)
				)
				(justify mirror)
			)
		)
		(property "Value" "SCD1U25V2KX-2-GP"
			(at -1.1811 -2.7051 270)
			(unlocked yes)
			(layer "B.Fab")
			(hide yes)
			(effects
				(font
					(size 1.016 1.016)
					(thickness 0.1524)
				)
				(justify mirror)
			)
		)
		(property "Device Type" "C402H22"
			(at -1.1811 -4.2291 270)
			(unlocked yes)
			(layer "B.Fab")
			(hide yes)
			(effects
				(font
					(size 1.016 1.016)
					(thickness 0.1524)
				)
				(justify mirror)
			)
		)
		(duplicate_pad_numbers_are_jumpers no)
		(fp_rect
			(start 0.4318 0.9525)
			(end -0.4318 -0.9525)
			(stroke
				(width 0)
				(type default)
			)
			(fill no)
			(layer "B.CrtYd")
		)
		(fp_rect
			(start 0.4318 0.9525)
			(end -0.4318 -0.9525)
			(stroke
				(width 0)
				(type default)
			)
			(fill no)
			(layer "B.Fab")
		)
		(pad "1" smd custom
			(at 0 -0.4445 90)
			(size 0.1524 0.1524)
			(layers "B.Cu" "B.Mask" "B.Paste")
			(net "P1V8_STBY")
			(options
				(clearance outline)
				(anchor circle)
			)
			(primitives
				(gr_poly
					(pts
						(arc
							(start 0.3048 0.2032)
							(mid 0.275042 0.275042)
							(end 0.2032 0.3048)
						)
						(arc
							(start -0.2032 0.3048)
							(mid -0.275042 0.275042)
							(end -0.3048 0.2032)
						)
						(arc
							(start -0.3048 -0.2032)
							(mid -0.275042 -0.275042)
							(end -0.2032 -0.3048)
						)
						(arc
							(start 0.2032 -0.3048)
							(mid 0.275042 -0.275042)
							(end 0.3048 -0.2032)
						)
					)
					(width 0)
					(fill yes)
				)
			)
		)
		(pad "2" smd custom
			(at 0 0.4445 90)
			(size 0.1524 0.1524)
			(layers "B.Cu" "B.Mask" "B.Paste")
			(net "P1V8_STBY_LL_R")
			(options
				(clearance outline)
				(anchor circle)
			)
			(primitives
				(gr_poly
					(pts
						(arc
							(start 0.3048 0.2032)
							(mid 0.275042 0.275042)
							(end 0.2032 0.3048)
						)
						(arc
							(start -0.2032 0.3048)
							(mid -0.275042 0.275042)
							(end -0.3048 0.2032)
						)
						(arc
							(start -0.3048 -0.2032)
							(mid -0.275042 -0.275042)
							(end -0.2032 -0.3048)
						)
						(arc
							(start 0.2032 -0.3048)
							(mid 0.275042 -0.275042)
							(end 0.3048 -0.2032)
						)
					)
					(width 0)
					(fill yes)
				)
			)
		)
	)
	(footprint ""
		(layer "B.Cu")
		(at 115.894612 -204.978 180)
		(property "Reference" "SR892"
			(at 0 0 0)
			(layer "B.SilkS")
			(hide yes)
			(effects
				(font
					(size 1.27 1.27)
				)
				(justify mirror)
			)
		)
		(property "Value" "0R2J-2-GP"
			(at -0.064008 -3.993896 180)
			(unlocked yes)
			(layer "B.Fab")
			(hide yes)
			(effects
				(font
					(size 1.016 1.016)
					(thickness 0.1524)
				)
				(justify mirror)
			)
		)
		(property "Device Type" "R402H16"
			(at -0.064008 -5.517896 180)
			(unlocked yes)
			(layer "B.Fab")
			(hide yes)
			(effects
				(font
					(size 1.016 1.016)
					(thickness 0.1524)
				)
				(justify mirror)
			)
		)
		(duplicate_pad_numbers_are_jumpers no)
		(fp_line
			(start 0.508 -0.9398)
			(end 0.508 0.9398)
			(stroke
				(width 0.1524)
				(type default)
			)
			(layer "B.SilkS")
		)
		(fp_line
			(start -0.508 -0.9398)
			(end 0.508 -0.9398)
			(stroke
				(width 0.1524)
				(type default)
			)
			(layer "B.SilkS")
		)
		(fp_rect
			(start 0.508 0.9398)
			(end -0.508 -0.9398)
			(stroke
				(width 0)
				(type default)
			)
			(fill no)
			(layer "B.CrtYd")
		)
		(fp_rect
			(start 0.508 0.9398)
			(end -0.508 -0.9398)
			(stroke
				(width 0)
				(type default)
			)
			(fill no)
			(layer "B.Fab")
		)
		(pad "1" smd custom
			(at 0 -0.4445)
			(size 0.1397 0.1397)
			(layers "B.Cu" "B.Mask" "B.Paste")
			(net "REDV_RX7_N")
			(options
				(clearance outline)
				(anchor circle)
			)
			(primitives
				(gr_poly
					(pts
						(arc
							(start -0.1778 0.2794)
							(mid -0.249642 0.249642)
							(end -0.2794 0.1778)
						)
						(arc
							(start -0.2794 -0.1778)
							(mid -0.249642 -0.249642)
							(end -0.1778 -0.2794)
						)
						(arc
							(start 0.1778 -0.2794)
							(mid 0.249642 -0.249642)
							(end 0.2794 -0.1778)
						)
						(arc
							(start 0.2794 0.1778)
							(mid 0.249642 0.249642)
							(end 0.1778 0.2794)
						)
					)
					(width 0)
					(fill yes)
				)
			)
		)
		(pad "2" smd custom
			(at 0 0.4445)
			(size 0.1397 0.1397)
			(layers "B.Cu" "B.Mask" "B.Paste")
			(net "SAS_HDD_CONN_RX7_N")
			(options
				(clearance outline)
				(anchor circle)
			)
			(primitives
				(gr_poly
					(pts
						(arc
							(start -0.1778 0.2794)
							(mid -0.249642 0.249642)
							(end -0.2794 0.1778)
						)
						(arc
							(start -0.2794 -0.1778)
							(mid -0.249642 -0.249642)
							(end -0.1778 -0.2794)
						)
						(arc
							(start 0.1778 -0.2794)
							(mid 0.249642 -0.249642)
							(end 0.2794 -0.1778)
						)
						(arc
							(start 0.2794 0.1778)
							(mid 0.249642 0.249642)
							(end 0.1778 0.2794)
						)
					)
					(width 0)
					(fill yes)
				)
			)
		)
	)
	(footprint ""
		(layer "B.Cu")
		(at 125.99797 -102.997 90)
		(property "Reference" "SC1162"
			(at 0 0 90)
			(layer "B.SilkS")
			(hide yes)
			(effects
				(font
					(size 1.27 1.27)
				)
				(justify mirror)
			)
		)
		(property "Value" "SCD1U6D3V1KX-GP"
			(at 2.8321 -1.7399 90)
			(unlocked yes)
			(layer "B.Fab")
			(hide yes)
			(effects
				(font
					(size 1.016 1.016)
					(thickness 0.1524)
				)
				(justify mirror)
			)
		)
		(property "Device Type" "C0201H13"
			(at 2.8321 -3.2639 90)
			(unlocked yes)
			(layer "B.Fab")
			(hide yes)
			(effects
				(font
					(size 1.016 1.016)
					(thickness 0.1524)
				)
				(justify mirror)
			)
		)
		(duplicate_pad_numbers_are_jumpers no)
		(fp_rect
			(start 0.2794 0.6477)
			(end -0.2794 -0.6477)
			(stroke
				(width 0)
				(type default)
			)
			(fill no)
			(layer "B.CrtYd")
		)
		(fp_rect
			(start 0.2794 0.6477)
			(end -0.2794 -0.6477)
			(stroke
				(width 0)
				(type default)
			)
			(fill no)
			(layer "B.Fab")
		)
		(pad "1" smd custom
			(at 0 -0.2794 270)
			(size 0.0762 0.0762)
			(layers "B.Cu" "B.Mask" "B.Paste")
			(net "GB_VDDA")
			(options
				(clearance outline)
				(anchor circle)
			)
			(primitives
				(gr_poly
					(pts
						(arc
							(start 0.1524 0.127)
							(mid 0.137521 0.162921)
							(end 0.1016 0.1778)
						)
						(arc
							(start -0.1016 0.1778)
							(mid -0.137521 0.162921)
							(end -0.1524 0.127)
						)
						(arc
							(start -0.1524 -0.127)
							(mid -0.137521 -0.162921)
							(end -0.1016 -0.1778)
						)
						(arc
							(start 0.1016 -0.1778)
							(mid 0.137521 -0.162921)
							(end 0.1524 -0.127)
						)
					)
					(width 0)
					(fill yes)
				)
			)
		)
		(pad "2" smd custom
			(at 0 0.2794 270)
			(size 0.0762 0.0762)
			(layers "B.Cu" "B.Mask" "B.Paste")
			(net "GND")
			(options
				(clearance outline)
				(anchor circle)
			)
			(primitives
				(gr_poly
					(pts
						(arc
							(start 0.1524 0.127)
							(mid 0.137521 0.162921)
							(end 0.1016 0.1778)
						)
						(arc
							(start -0.1016 0.1778)
							(mid -0.137521 0.162921)
							(end -0.1524 0.127)
						)
						(arc
							(start -0.1524 -0.127)
							(mid -0.137521 -0.162921)
							(end -0.1016 -0.1778)
						)
						(arc
							(start 0.1016 -0.1778)
							(mid 0.137521 -0.162921)
							(end 0.1524 -0.127)
						)
					)
					(width 0)
					(fill yes)
				)
			)
		)
	)
	(footprint ""
		(layer "B.Cu")
		(at 141.36497 -87.249 180)
		(property "Reference" "R176"
			(at 0 0 0)
			(layer "B.SilkS")
			(hide yes)
			(effects
				(font
					(size 1.27 1.27)
				)
				(justify mirror)
			)
		)
		(property "Value" "4K7R2F-GP"
			(at -0.064008 -3.993896 180)
			(unlocked yes)
			(layer "B.Fab")
			(hide yes)
			(effects
				(font
					(size 1.016 1.016)
					(thickness 0.1524)
				)
				(justify mirror)
			)
		)
		(property "Device Type" "R402H16"
			(at -0.064008 -5.517896 180)
			(unlocked yes)
			(layer "B.Fab")
			(hide yes)
			(effects
				(font
					(size 1.016 1.016)
					(thickness 0.1524)
				)
				(justify mirror)
			)
		)
		(duplicate_pad_numbers_are_jumpers no)
		(fp_line
			(start 0.508 -0.9398)
			(end 0.508 0.9398)
			(stroke
				(width 0.1524)
				(type default)
			)
			(layer "B.SilkS")
		)
		(fp_line
			(start -0.508 -0.9398)
			(end 0.508 -0.9398)
			(stroke
				(width 0.1524)
				(type default)
			)
			(layer "B.SilkS")
		)
		(fp_rect
			(start 0.508 0.9398)
			(end -0.508 -0.9398)
			(stroke
				(width 0)
				(type default)
			)
			(fill no)
			(layer "B.CrtYd")
		)
		(fp_rect
			(start 0.508 0.9398)
			(end -0.508 -0.9398)
			(stroke
				(width 0)
				(type default)
			)
			(fill no)
			(layer "B.Fab")
		)
		(pad "1" smd custom
			(at 0 -0.4445)
			(size 0.1397 0.1397)
			(layers "B.Cu" "B.Mask" "B.Paste")
			(net "TEMP_3_A0")
			(options
				(clearance outline)
				(anchor circle)
			)
			(primitives
				(gr_poly
					(pts
						(arc
							(start -0.1778 0.2794)
							(mid -0.249642 0.249642)
							(end -0.2794 0.1778)
						)
						(arc
							(start -0.2794 -0.1778)
							(mid -0.249642 -0.249642)
							(end -0.1778 -0.2794)
						)
						(arc
							(start 0.1778 -0.2794)
							(mid 0.249642 -0.249642)
							(end 0.2794 -0.1778)
						)
						(arc
							(start 0.2794 0.1778)
							(mid 0.249642 0.249642)
							(end 0.1778 0.2794)
						)
					)
					(width 0)
					(fill yes)
				)
			)
		)
		(pad "2" smd custom
			(at 0 0.4445)
			(size 0.1397 0.1397)
			(layers "B.Cu" "B.Mask" "B.Paste")
			(net "GND")
			(options
				(clearance outline)
				(anchor circle)
			)
			(primitives
				(gr_poly
					(pts
						(arc
							(start -0.1778 0.2794)
							(mid -0.249642 0.249642)
							(end -0.2794 0.1778)
						)
						(arc
							(start -0.2794 -0.1778)
							(mid -0.249642 -0.249642)
							(end -0.1778 -0.2794)
						)
						(arc
							(start 0.1778 -0.2794)
							(mid 0.249642 -0.249642)
							(end 0.2794 -0.1778)
						)
						(arc
							(start 0.2794 0.1778)
							(mid 0.249642 0.249642)
							(end 0.1778 0.2794)
						)
					)
					(width 0)
					(fill yes)
				)
			)
		)
	)
)
